# T6G (Grand Teton) — schematic netlist excerpt (pin names and nets, part order shuffled) for the footprints in the layout excerpt that follows; sources: Cadence DE-HDL packaged netlist, KiCad conversion of 04192023_DAF0TMB3IC0_F0TG_MB_C_brd_V02_OCP.brd

J100  SCONN288_DDR506112002KQ  IO  pkg DDR288S_1-1VXC  page 106
  VIN_BULK0  = P12V_MEM_CPU1
  RFU0  = NC
  VIN_MGMT  = P3V3_AUX
  HSCL  = I3C_SPD_DDRI_CPU1_SCL
  HSDA  = I3C_SPD_DDRI_CPU1_SDA
  VSS0  = GND
  DQ0_A  = M_I_CPU1_SA_DQ<0>
  VSS1  = GND
  DQ1_A  = M_I_CPU1_SA_DQ<1>
  VSS2  = GND
  DQS0_A_T  = M_I_CPU1_SA_DQS_DP<0>
  DQS0_A_C  = M_I_CPU1_SA_DQS_DN<0>
  VSS3  = GND
  DQ4_A  = M_I_CPU1_SA_DQ<4>
  VSS4  = GND
  DQ5_A  = M_I_CPU1_SA_DQ<5>
  VSS5  = GND
  DQ8_A  = M_I_CPU1_SA_DQ<8>
  VSS6  = GND
  DQ9_A  = M_I_CPU1_SA_DQ<9>
  VSS7  = GND
  DQS1_A_T  = M_I_CPU1_SA_DQS_DP<1>
  DQS1_A_C  = M_I_CPU1_SA_DQS_DN<1>
  VSS8  = GND
  DQ12_A  = M_I_CPU1_SA_DQ<12>
  VSS9  = GND
  DQ13_A  = M_I_CPU1_SA_DQ<13>
  VSS10  = GND
  DQ16_A  = M_I_CPU1_SA_DQ<16>
  VSS11  = GND
  DQ17_A  = M_I_CPU1_SA_DQ<17>
  VSS12  = GND
  DQS2_A_T  = M_I_CPU1_SA_DQS_DP<2>
  DQS2_A_C  = M_I_CPU1_SA_DQS_DN<2>
  VSS13  = GND
  DQ20_A  = M_I_CPU1_SA_DQ<20>
  VSS14  = GND
  DQ21_A  = M_I_CPU1_SA_DQ<21>
  VSS15  = GND
  DQ24_A  = M_I_CPU1_SA_DQ<24>
  VSS16  = GND
  DQ25_A  = M_I_CPU1_SA_DQ<25>
  VSS17  = GND
  DQS3_A_T  = M_I_CPU1_SA_DQS_DP<3>
  DQS3_A_C  = M_I_CPU1_SA_DQS_DN<3>
  VSS18  = GND
  DQ28_A  = M_I_CPU1_SA_DQ<28>
  VSS19  = GND
  DQ29_A  = M_I_CPU1_SA_DQ<29>
  VSS20  = GND
  CB0_A  = M_I_CPU1_SA_CB<0>
  VSS21  = GND
  CB1_A  = M_I_CPU1_SA_CB<1>
  VSS22  = GND
  DQS4_A_T  = M_I_CPU1_SA_DQS_DP<4>
  DQS4_A_C  = M_I_CPU1_SA_DQS_DN<4>
  VSS23  = GND
  CB4_A  = M_I_CPU1_SA_CB<4>
  VSS24  = GND
  CB5_A  = M_I_CPU1_SA_CB<5>
  VSS25  = GND
  ALERT_N  = M_I_CPU1_ALERT_N
  VSS26  = GND
  CS0_A_N  = M_I_CPU1_SA_CS_N<0>
  VSS27  = GND
  CA0_A  = M_I_CPU1_SA_CA<0>
  VSS28  = GND
  CA2_A  = M_I_CPU1_SA_CA<2>
  VSS29  = GND
  CA4_A  = M_I_CPU1_SA_CA<4>
  VSS30  = GND
  CA6_A  = M_I_CPU1_SA_CA<6>
  VSS31  = GND
  PAR_A  = M_I_CPU1_SA_PAR
  VSS32  = GND
  CA0_B  = M_I_CPU1_SB_CA<0>
  VSS33  = GND
  CA2_B  = M_I_CPU1_SB_CA<2>
  VSS34  = GND
  CA4_B  = M_I_CPU1_SB_CA<4>
  VSS35  = GND
  CA6_B  = M_I_CPU1_SB_CA<6>
  VSS36  = GND
  CS0_B_N  = M_I_CPU1_SB_CS_N<0>
  VSS37  = GND
  \lbd||rsp_a_n\  = M_I_CPU1_SA_RSP<0>
  \lbs||rsp_b_n\  = M_I_CPU1_SB_RSP<0>
  VSS38  = GND
  CB4_B  = M_I_CPU1_SB_CB<4>
  VSS39  = GND
  CB5_B  = M_I_CPU1_SB_CB<5>
  VSS40  = GND
  \dqs9_b_t||tdqs9_b_t||dbi4_b_n\  = M_I_CPU1_SB_DQS_DP<9>
  \dqs9_b_c||tdqs9_b_c\  = M_I_CPU1_SB_DQS_DN<9>
  VSS41  = GND
  CB0_B  = M_I_CPU1_SB_CB<0>
  VSS42  = GND
  CB1_B  = M_I_CPU1_SB_CB<1>
  VSS43  = GND
  DQ0_B  = M_I_CPU1_SB_DQ<0>
  VSS44  = GND
  DQ1_B  = M_I_CPU1_SB_DQ<1>
  VSS45  = GND
  DQS0_B_T  = M_I_CPU1_SB_DQS_DP<0>
  DQS0_B_C  = M_I_CPU1_SB_DQS_DN<0>
  VSS46  = GND
  DQ4_B  = M_I_CPU1_SB_DQ<4>
  VSS47  = GND
  DQ5_B  = M_I_CPU1_SB_DQ<5>
  VSS48  = GND
  DQ8_B  = M_I_CPU1_SB_DQ<8>
  VSS49  = GND
  DQ9_B  = M_I_CPU1_SB_DQ<9>
  VSS50  = GND
  DQS1_B_T  = M_I_CPU1_SB_DQS_DP<1>
  DQS1_B_C  = M_I_CPU1_SB_DQS_DN<1>
  VSS51  = GND
  DQ12_B  = M_I_CPU1_SB_DQ<12>
  VSS52  = GND
  DQ13_B  = M_I_CPU1_SB_DQ<13>
  VSS53  = GND
  DQ16_B  = M_I_CPU1_SB_DQ<16>
  VSS54  = GND
  DQ17_B  = M_I_CPU1_SB_DQ<17>
  VSS55  = GND
  DQS2_B_T  = M_I_CPU1_SB_DQS_DP<2>
  DQS2_B_C  = M_I_CPU1_SB_DQS_DN<2>
  VSS56  = GND
  DQ20_B  = M_I_CPU1_SB_DQ<20>
  VSS57  = GND
  DQ21_B  = M_I_CPU1_SB_DQ<21>
  VSS58  = GND
  DQ24_B  = M_I_CPU1_SB_DQ<24>
  VSS59  = GND
  DQ25_B  = M_I_CPU1_SB_DQ<25>
  VSS60  = GND
  DQS3_B_T  = M_I_CPU1_SB_DQS_DP<3>
  DQS3_B_C  = M_I_CPU1_SB_DQS_DN<3>
  VSS61  = GND
  DQ28_B  = M_I_CPU1_SB_DQ<28>
  VSS62  = GND
  DQ29_B  = M_I_CPU1_SB_DQ<29>
  VSS63  = GND
  RFU1  = NC
  VIN_BULK1  = P12V_MEM_CPU1
  VIN_BULK2  = P12V_MEM_CPU1
  \pwr_good||fail_n\  = PWRGD_CHI_CPU1_DIMM
  HAS  = PD_CHI_CPU1_DIMM_SAA
  RFU2  = NC
  RFU3  = NC
  VSS64  = GND
  DQ2_A  = M_I_CPU1_SA_DQ<2>
  VSS65  = GND
  DQ3_A  = M_I_CPU1_SA_DQ<3>
  VSS66  = GND
  \dqs5_a_c||tdqs5_a_c||dqs5_a_t||tdqs5_a_t\  = M_I_CPU1_SA_DQS_DN<5>
  \dqs5_a_t||tdqs5_a_t\  = M_I_CPU1_SA_DQS_DP<5>
  VSS67  = GND
  DQ6_A  = M_I_CPU1_SA_DQ<6>
  VSS68  = GND
  DQ7_A  = M_I_CPU1_SA_DQ<7>
  VSS69  = GND
  DQ10_A  = M_I_CPU1_SA_DQ<10>
  VSS70  = GND
  DQ11_A  = M_I_CPU1_SA_DQ<11>
  VSS71  = GND
  \dqs6_a_c||tdqs6_a_c||dqs6_a_t||tdqs6_a_t\  = M_I_CPU1_SA_DQS_DN<6>
  \dqs6_a_t||tdqs6_a_t\  = M_I_CPU1_SA_DQS_DP<6>
  VSS72  = GND
  DQ14_A  = M_I_CPU1_SA_DQ<14>
  VSS73  = GND
  DQ15_A  = M_I_CPU1_SA_DQ<15>
  VSS74  = GND
  DQ18_A  = M_I_CPU1_SA_DQ<18>
  VSS75  = GND
  DQ19_A  = M_I_CPU1_SA_DQ<19>
  VSS76  = GND
  \dqs7_a_c||tdqs7_a_c\  = M_I_CPU1_SA_DQS_DN<7>
  \dqs7_a_t||tdqs7_a_t\  = M_I_CPU1_SA_DQS_DP<7>
  VSS77  = GND
  DQ22_A  = M_I_CPU1_SA_DQ<22>
  VSS78  = GND
  DQ23_A  = M_I_CPU1_SA_DQ<23>
  VSS79  = GND
  DQ26_A  = M_I_CPU1_SA_DQ<26>
  VSS80  = GND
  DQ27_A  = M_I_CPU1_SA_DQ<27>
  VSS81  = GND
  \dqs8_a_c||tdqs8_a_c\  = M_I_CPU1_SA_DQS_DN<8>
  \dqs8_a_t||tdqs8_a_t\  = M_I_CPU1_SA_DQS_DP<8>
  VSS82  = GND
  DQ30_A  = M_I_CPU1_SA_DQ<30>
  VSS83  = GND
  DQ31_A  = M_I_CPU1_SA_DQ<31>
  VSS84  = GND
  CB2_A  = M_I_CPU1_SA_CB<2>
  VSS85  = GND
  CB3_A  = M_I_CPU1_SA_CB<3>
  VSS86  = GND
  \dqs9_a_c||tdqs9_a_c\  = M_I_CPU1_SA_DQS_DN<9>
  \dqs9_a_t||tdqs9_a_t\  = M_I_CPU1_SA_DQS_DP<9>
  VSS87  = GND
  CB6_A  = M_I_CPU1_SA_CB<6>
  VSS88  = GND
  CB7_A  = M_I_CPU1_SA_CB<7>
  VSS89  = GND
  RESET_N  = M_I_CPU1_RESET_N
  VSS90  = GND
  CS1_A_N  = M_I_CPU1_SA_CS_N<1>
  VSS91  = GND
  CA1_A  = M_I_CPU1_SA_CA<1>
  VSS92  = GND
  CA3_A  = M_I_CPU1_SA_CA<3>
  VSS93  = GND
  CA5_A  = M_I_CPU1_SA_CA<5>
  VSS94  = GND
  CK_T  = M_I_CPU1_CLK_DP<0>
  CK_C  = M_I_CPU1_CLK_DN<0>
  VSS95  = GND
  RFU4  = NC
  CA1_B  = M_I_CPU1_SB_CA<1>
  VSS96  = GND
  CA3_B  = M_I_CPU1_SB_CA<3>
  VSS97  = GND
  CA5_B  = M_I_CPU1_SB_CA<5>
  VSS98  = GND
  PAR_B  = M_I_CPU1_SB_PAR
  VSS99  = GND
  CS1_B_N  = M_I_CPU1_SB_CS_N<1>
  VSS100  = GND
  RFU5  = NC
  RFU6  = NC
  VSS101  = GND
  CB6_B  = M_I_CPU1_SB_CB<6>
  VSS102  = GND
  CB7_B  = M_I_CPU1_SB_CB<7>
  VSS103  = GND
  DQS4_B_C  = M_I_CPU1_SB_DQS_DN<4>
  DQS4_B_T  = M_I_CPU1_SB_DQS_DP<4>
  VSS104  = GND
  CB2_B  = M_I_CPU1_SB_CB<2>
  VSS105  = GND
  CB3_B  = M_I_CPU1_SB_CB<3>
  VSS106  = GND
  DQ2_B  = M_I_CPU1_SB_DQ<2>
  VSS107  = GND
  DQ3_B  = M_I_CPU1_SB_DQ<3>
  VSS108  = GND
  \dqs5_b_c||tdqs5_b_c\  = M_I_CPU1_SB_DQS_DN<5>
  \dqs5_b_t||tdqs5_b_t\  = M_I_CPU1_SB_DQS_DP<5>
  VSS109  = GND
  DQ6_B  = M_I_CPU1_SB_DQ<6>
  VSS110  = GND
  DQ7_B  = M_I_CPU1_SB_DQ<7>
  VSS111  = GND
  DQ10_B  = M_I_CPU1_SB_DQ<10>
  VSS112  = GND
  DQ11_B  = M_I_CPU1_SB_DQ<11>
  VSS113  = GND
  \dqs6_b_c||tdqs6_b_c\  = M_I_CPU1_SB_DQS_DN<6>
  \dqs6_b_t||tdqs6_b_t\  = M_I_CPU1_SB_DQS_DP<6>
  VSS114  = GND
  DQ14_B  = M_I_CPU1_SB_DQ<14>
  VSS115  = GND
  DQ15_B  = M_I_CPU1_SB_DQ<15>
  VSS116  = GND
  DQ18_B  = M_I_CPU1_SB_DQ<18>
  VSS117  = GND
  DQ19_B  = M_I_CPU1_SB_DQ<19>
  VSS118  = GND
  \dqs7_b_c||tdqs7_b_c\  = M_I_CPU1_SB_DQS_DN<7>
  \dqs7_b_t||tdqs7_b_t\  = M_I_CPU1_SB_DQS_DP<7>
  VSS119  = GND
  DQ22_B  = M_I_CPU1_SB_DQ<22>
  VSS120  = GND
  DQ23_B  = M_I_CPU1_SB_DQ<23>
  VSS121  = GND
  DQ26_B  = M_I_CPU1_SB_DQ<26>
  VSS122  = GND
  DQ27_B  = M_I_CPU1_SB_DQ<27>
  VSS123  = GND
  \dqs8_b_c||tdqs8_b_c\  = M_I_CPU1_SB_DQS_DN<8>
  \dqs8_b_t||tdqs8_b_t\  = M_I_CPU1_SB_DQS_DP<8>
  VSS124  = GND
  DQ30_B  = M_I_CPU1_SB_DQ<30>
  VSS125  = GND
  DQ31_B  = M_I_CPU1_SB_DQ<31>
  VSS126  = GND
  G1  = GND
  G2  = GND
  G3  = GND

(kicad_pcb
	(version 20260206)
	(generator "pcbnew")
	(generator_version "10.0")
	(general
		(thickness 1.6)
		(legacy_teardrops no)
	)
	(paper "A4")
	(title_block
		(title "04192023_DAF0TMB3IC0_F0TG_MB_C_brd_V02_OCP.brd")
		(comment 1 "Grand Teton / footprint 230 of 8354 (J100), pads 277-291 of 291")
	)
	(layers
		(0 "F.Cu" signal "TOP")
		(4 "In1.Cu" signal "GND")
		(6 "In2.Cu" signal "IN1")
		(8 "In3.Cu" signal "GND1")
		(10 "In4.Cu" signal "IN2")
		(12 "In5.Cu" signal "GND2")
		(14 "In6.Cu" signal "IN3")
		(16 "In7.Cu" signal "GND3")
		(18 "In8.Cu" signal "VCC")
		(20 "In9.Cu" signal "VCC1")
		(22 "In10.Cu" signal "GND4")
		(24 "In11.Cu" signal "IN4")
		(26 "In12.Cu" signal "GND5")
		(28 "In13.Cu" signal "IN5")
		(30 "In14.Cu" signal "GND6")
		(32 "In15.Cu" signal "IN6")
		(34 "In16.Cu" signal "GND7")
		(2 "B.Cu" signal "BOTTOM")
		(9 "F.Adhes" user "F.Adhesive")
		(11 "B.Adhes" user "B.Adhesive")
		(13 "F.Paste" user "Package Geometry/Pastemask Top")
		(15 "B.Paste" user "Package Geometry/Pastemask Bottom")
		(5 "F.SilkS" user "Ref Des/Silkscreen Top")
		(7 "B.SilkS" user "Ref Des/Silkscreen Bottom")
		(1 "F.Mask" user "Board Geometry/Soldermask Top")
		(3 "B.Mask" user "Board Geometry/Soldermask Bottom")
		(17 "Dwgs.User" user "User.Drawings")
		(19 "Cmts.User" user "User.Comments")
		(21 "Eco1.User" user "User.Eco1")
		(23 "Eco2.User" user "User.Eco2")
		(25 "Edge.Cuts" user "Board Geometry/Outline")
		(27 "Margin" user)
		(31 "F.CrtYd" user "Package Geometry/Place Bound Top")
		(29 "B.CrtYd" user "Package Geometry/Place Bound Bottom")
		(35 "F.Fab" user "Ref Des/Assembly Top")
		(33 "B.Fab" user "Ref Des/Assembly Bottom")
	)
	(footprint ""
		(layer "F.Cu")
		(at 181.566058 -255.560322 180)
		(property "Reference" "J100"
			(at -2.7178 -81.857088 0)
			(unlocked yes)
			(layer "F.SilkS")
			(effects
				(font
					(size 0.7874 0.5842)
					(thickness 0.1524)
				)
			)
		)
		(property "Value" ""
			(at 0 0 180)
			(layer "F.Fab")
			(effects
				(font
					(size 1.27 1.27)
				)
			)
		)
		(duplicate_pad_numbers_are_jumpers no)
		(pad "277" smd rect
			(at 2.050034 53.975 90)
			(size 0.519938 1.4986)
			(layers "F.Cu" "F.Mask" "F.Paste")
			(net "GND")
		)
		(pad "278" smd rect
			(at 2.050034 54.824884 90)
			(size 0.519938 1.4986)
			(layers "F.Cu" "F.Mask" "F.Paste")
			(net "M_I_CPU1_SB_DQ<26>")
		)
		(pad "279" smd rect
			(at 2.050034 55.675022 90)
			(size 0.519938 1.4986)
			(layers "F.Cu" "F.Mask" "F.Paste")
			(net "GND")
		)
		(pad "280" smd rect
			(at 2.050034 56.524906 90)
			(size 0.519938 1.4986)
			(layers "F.Cu" "F.Mask" "F.Paste")
			(net "M_I_CPU1_SB_DQ<27>")
		)
		(pad "281" smd rect
			(at 2.050034 57.375044 90)
			(size 0.519938 1.4986)
			(layers "F.Cu" "F.Mask" "F.Paste")
			(net "GND")
		)
		(pad "282" smd rect
			(at 2.050034 58.224928 90)
			(size 0.519938 1.4986)
			(layers "F.Cu" "F.Mask" "F.Paste")
			(net "M_I_CPU1_SB_DQS_DN<8>")
		)
		(pad "283" smd rect
			(at 2.050034 59.075066 90)
			(size 0.519938 1.4986)
			(layers "F.Cu" "F.Mask" "F.Paste")
			(net "M_I_CPU1_SB_DQS_DP<8>")
		)
		(pad "284" smd rect
			(at 2.050034 59.92495 90)
			(size 0.519938 1.4986)
			(layers "F.Cu" "F.Mask" "F.Paste")
			(net "GND")
		)
		(pad "285" smd rect
			(at 2.050034 60.775088 90)
			(size 0.519938 1.4986)
			(layers "F.Cu" "F.Mask" "F.Paste")
			(net "M_I_CPU1_SB_DQ<30>")
		)
		(pad "286" smd rect
			(at 2.050034 61.624972 90)
			(size 0.519938 1.4986)
			(layers "F.Cu" "F.Mask" "F.Paste")
			(net "GND")
		)
		(pad "287" smd rect
			(at 2.050034 62.47511 90)
			(size 0.519938 1.4986)
			(layers "F.Cu" "F.Mask" "F.Paste")
			(net "M_I_CPU1_SB_DQ<31>")
		)
		(pad "288" smd rect
			(at 2.050034 63.324994 90)
			(size 0.519938 1.4986)
			(layers "F.Cu" "F.Mask" "F.Paste")
			(net "GND")
		)
		(pad "G1" thru_hole oval
			(at 0 -68.97497 90)
			(size 1.7272 3.4798)
			(drill oval 1.2192 2.4638)
			(layers "*.Cu" "*.Mask")
			(remove_unused_layers no)
			(net "GND")
			(clearance 0.127)
			(thermal_gap 0.127)
		)
		(pad "G2" thru_hole oval
			(at 0 3.875024 90)
			(size 1.7272 3.4798)
			(drill oval 1.2192 2.4638)
			(layers "*.Cu" "*.Mask")
			(remove_unused_layers no)
			(net "GND")
			(clearance 0.127)
			(thermal_gap 0.127)
		)
		(pad "G3" thru_hole oval
			(at 0 68.97497 90)
			(size 1.7272 3.4798)
			(drill oval 1.2192 2.4638)
			(layers "*.Cu" "*.Mask")
			(remove_unused_layers no)
			(net "GND")
			(clearance 0.127)
			(thermal_gap 0.127)
		)
	)
)
